(kicad_pcb
	(version 20221018)
	(generator pcbnew)
	(general
    (thickness 1.518)
  )
	(paper "A4")
	(title_block
    (title "Kria K26 Devboard")
    (date "2024-03-26")
    (rev "1.2.5")
    (comment 1 "www.antmicro.com")
    (comment 2 "Antmicro Ltd.")
		(comment 9 "footprints 90-96 of 660")
	)
	(layers
    (0 "F.Cu" mixed)
    (1 "In1.Cu" power)
    (2 "In2.Cu" mixed)
    (3 "In3.Cu" power)
    (4 "In4.Cu" mixed)
    (5 "In5.Cu" power)
    (6 "In6.Cu" mixed)
    (31 "B.Cu" power)
    (32 "B.Adhes" user "B.Adhesive")
    (33 "F.Adhes" user "F.Adhesive")
    (34 "B.Paste" user)
    (35 "F.Paste" user)
    (36 "B.SilkS" user "B.Silkscreen")
    (37 "F.SilkS" user "F.Silkscreen")
    (38 "B.Mask" user)
    (39 "F.Mask" user)
    (40 "Dwgs.User" user "User.Drawings")
    (41 "Cmts.User" user "User.Comments")
    (42 "Eco1.User" user "User.Eco1")
    (43 "Eco2.User" user "User.Eco2")
    (44 "Edge.Cuts" user)
    (45 "Margin" user)
    (46 "B.CrtYd" user "B.Courtyard")
    (47 "F.CrtYd" user "F.Courtyard")
    (48 "B.Fab" user)
    (49 "F.Fab" user)
  )
	(footprint "kria-k26-devboard-footprints:SOIC-8_3.9x4.9x1.75mm_P1.27mm" (layer "F.Cu")
    (at 99.4 133.95)
    (tags "Integrated Circuit")
    (property "Author" "Antmicro")
    (property "License" "Apache-2.0")
    (property "MPN" "PCA9306D,118")
    (property "Manufacturer" "NXP")
    (property "Sheetfile" "i2c.kicad_sch")
    (property "Sheetname" "I2C ")
    (property "ki_description" "Specialized Interface, I2C, SMBus, I2C Bus & SMBus Systems Applications, 0 V, 5 V, SOIC, 8 Pins")
    (property "ki_keywords" "SMT, LEVEL-SHIFTER, IC")
    (attr smd)
    (fp_text reference "U12" (at 0 -2.85) (layer "F.SilkS")
        (effects (font (size 0.7 0.7) (thickness 0.15)) (justify left bottom))
    )
    (fp_text value "PCA9306D_SOIC" (at 0 3.65) (layer "F.Fab")
        (effects (font (size 0.7 0.7) (thickness 0.15)) (justify left bottom))
    )
    (fp_text user "License: Apache-2.0" (at -3.476 5.099) (layer "F.Fab") hide
        (effects (font (size 0.7 0.7) (thickness 0.15)) (justify left bottom))
    )
    (fp_text user "${REFERENCE}" (at -3.476 7.099) (layer "F.Fab") hide
        (effects (font (size 0.7 0.7) (thickness 0.15)) (justify left bottom))
    )
    (fp_text user "Author: Antmicro" (at -3.476 6.099) (layer "F.Fab") hide
        (effects (font (size 0.7 0.7) (thickness 0.15)) (justify left bottom))
    )
    (fp_line (start -1.95 -2.452) (end 1.95 -2.45)
      (stroke (width 0.15) (type solid)) (layer "F.SilkS"))
    (fp_line (start -1.95 2.45) (end 1.95 2.45)
      (stroke (width 0.15) (type solid)) (layer "F.SilkS"))
    (fp_circle (center -2.4 -2.45) (end -2.35 -2.4)
      (stroke (width 0.15) (type solid)) (fill solid) (layer "F.SilkS"))
    (fp_rect (start -3.625 -2.7) (end 3.625 2.7)
      (stroke (width 0.05) (type solid)) (fill none) (layer "F.CrtYd"))
    (fp_line (start -1.95 -1.18) (end -0.683 -2.452)
      (stroke (width 0.15) (type solid)) (layer "F.Fab"))
    (fp_line (start -1.95 2.45) (end -1.95 -1.18)
      (stroke (width 0.15) (type solid)) (layer "F.Fab"))
    (fp_line (start -0.683 -2.452) (end 1.949 -2.452)
      (stroke (width 0.15) (type solid)) (layer "F.Fab"))
    (fp_line (start 1.949 -2.452) (end 1.949 2.45)
      (stroke (width 0.15) (type solid)) (layer "F.Fab"))
    (fp_line (start 1.949 2.45) (end -1.95 2.45)
      (stroke (width 0.15) (type solid)) (layer "F.Fab"))
    (pad "1" smd roundrect (at -2.714 -1.905 90) (size 0.65 1.525) (layers "F.Cu" "F.Paste" "F.Mask") (roundrect_rratio 0.25)
      (net 1 "GND") (pinfunction "GND") (pintype "power_in"))
    (pad "2" smd roundrect (at -2.714 -0.635 90) (size 0.65 1.525) (layers "F.Cu" "F.Paste" "F.Mask") (roundrect_rratio 0.25)
      (net 17 "PS_1V8") (pinfunction "VREF_{1}") (pintype "power_in"))
    (pad "3" smd roundrect (at -2.714 0.632 90) (size 0.65 1.525) (layers "F.Cu" "F.Paste" "F.Mask") (roundrect_rratio 0.25)
      (net 153 "/I2C /MIO24_I2C_SCK") (pinfunction "SCL_{1}") (pintype "bidirectional"))
    (pad "4" smd roundrect (at -2.714 1.902 90) (size 0.65 1.525) (layers "F.Cu" "F.Paste" "F.Mask") (roundrect_rratio 0.25)
      (net 432 "/I2C /MIO25_I2C_SDA") (pinfunction "SDA_{1}") (pintype "bidirectional"))
    (pad "5" smd roundrect (at 2.712 1.902 90) (size 0.65 1.525) (layers "F.Cu" "F.Paste" "F.Mask") (roundrect_rratio 0.25)
      (net 163 "/I2C /I2C_SDA_3V3") (pinfunction "SDA_{2}") (pintype "bidirectional"))
    (pad "6" smd roundrect (at 2.712 0.632 90) (size 0.65 1.525) (layers "F.Cu" "F.Paste" "F.Mask") (roundrect_rratio 0.25)
      (net 162 "/I2C /I2C_SCK_3V3") (pinfunction "SCL_{2}") (pintype "bidirectional"))
    (pad "7" smd roundrect (at 2.712 -0.635 90) (size 0.65 1.525) (layers "F.Cu" "F.Paste" "F.Mask") (roundrect_rratio 0.25)
      (net 324 "/I2C /Vref2") (pinfunction "VREF_{2}") (pintype "power_in"))
    (pad "8" smd roundrect (at 2.712 -1.905 90) (size 0.65 1.525) (layers "F.Cu" "F.Paste" "F.Mask") (roundrect_rratio 0.25)
      (net 324 "/I2C /Vref2") (pinfunction "EN") (pintype "input"))
  )
	(footprint "kria-k26-devboard-footprints:C_0402_1005Metric" (layer "F.Cu")
    (at 95.2 132.65 90)
    (descr "Capacitor SMD 0402")
    (tags "capacitor SMD 0402")
    (property "Author" "Antmicro")
    (property "Dielectric" "X5R")
    (property "License" "Apache-2.0")
    (property "MPN" "GRM155R61H104KE14D")
    (property "Manufacturer" "Murata")
    (property "Sheetfile" "i2c.kicad_sch")
    (property "Sheetname" "I2C ")
    (property "Val" "100n")
    (property "Voltage" "50V")
    (property "ki_description" " ")
    (attr smd)
    (fp_text reference "C32" (at 0.82 0.31 90) (layer "F.SilkS")
        (effects (font (size 0.7 0.7) (thickness 0.15)) (justify left bottom))
    )
    (fp_text value "C_100n_0402" (at 0 1.4 90) (layer "F.Fab") hide
        (effects (font (size 0.7 0.7) (thickness 0.15)) (justify left bottom))
    )
    (fp_text user "${REFERENCE}" (at -0.932 3.168 90) (layer "F.Fab") hide
        (effects (font (size 0.7 0.7) (thickness 0.15)) (justify left bottom))
    )
    (fp_text user "Author: Antmicro" (at -0.932 4.17 90) (layer "F.Fab") hide
        (effects (font (size 0.7 0.7) (thickness 0.15)) (justify left bottom))
    )
    (fp_text user "License: Apache-2.0" (at -0.932 5.17 90) (layer "F.Fab") hide
        (effects (font (size 0.7 0.7) (thickness 0.15)) (justify left bottom))
    )
    (fp_rect (start -0.94 -0.47) (end 0.94 0.47)
      (stroke (width 0.05) (type solid)) (fill none) (layer "F.CrtYd"))
    (fp_rect (start -0.499 -0.249) (end 0.499 0.249)
      (stroke (width 0.15) (type solid)) (fill none) (layer "F.Fab"))
    (pad "1" smd roundrect (at -0.484 0 90) (size 0.59 0.64) (layers "F.Cu" "F.Paste" "F.Mask") (roundrect_rratio 0.25)
      (net 17 "PS_1V8") (pintype "passive"))
    (pad "2" smd roundrect (at 0.484 0 90) (size 0.59 0.64) (layers "F.Cu" "F.Paste" "F.Mask") (roundrect_rratio 0.25)
      (net 1 "GND") (pintype "passive"))
  )
	(footprint "kria-k26-devboard-footprints:C_0402_1005Metric" (layer "F.Cu")
    (at 129.975 83.45 90)
    (descr "Capacitor SMD 0402")
    (tags "capacitor SMD 0402")
    (property "Author" "Antmicro")
    (property "Dielectric" "")
    (property "License" "Apache-2.0")
    (property "MPN" "GRM155R61A475MEAAD")
    (property "Manufacturer" "Murata")
    (property "Sheetfile" "usb.kicad_sch")
    (property "Sheetname" "USB")
    (property "Val" "4u7")
    (property "Voltage" "")
    (property "ki_description" " ")
    (attr smd)
    (fp_text reference "C42" (at -1.12 1.295 90) (layer "F.SilkS")
        (effects (font (size 0.7 0.7) (thickness 0.15)) (justify left bottom))
    )
    (fp_text value "C_4u7_0402" (at 0 1.4 90) (layer "F.Fab") hide
        (effects (font (size 0.7 0.7) (thickness 0.15)) (justify left bottom))
    )
    (fp_text user "License: Apache-2.0" (at -0.932 5.17 90) (layer "F.Fab") hide
        (effects (font (size 0.7 0.7) (thickness 0.15)) (justify left bottom))
    )
    (fp_text user "Author: Antmicro" (at -0.932 4.17 90) (layer "F.Fab") hide
        (effects (font (size 0.7 0.7) (thickness 0.15)) (justify left bottom))
    )
    (fp_text user "${REFERENCE}" (at -0.932 3.168 90) (layer "F.Fab") hide
        (effects (font (size 0.7 0.7) (thickness 0.15)) (justify left bottom))
    )
    (fp_rect (start -0.94 -0.47) (end 0.94 0.47)
      (stroke (width 0.05) (type solid)) (fill none) (layer "F.CrtYd"))
    (fp_rect (start -0.499 -0.249) (end 0.499 0.249)
      (stroke (width 0.15) (type solid)) (fill none) (layer "F.Fab"))
    (pad "1" smd roundrect (at -0.484 0 90) (size 0.59 0.64) (layers "F.Cu" "F.Paste" "F.Mask") (roundrect_rratio 0.25)
      (net 15 "PS_3V3") (pintype "passive"))
    (pad "2" smd roundrect (at 0.484 0 90) (size 0.59 0.64) (layers "F.Cu" "F.Paste" "F.Mask") (roundrect_rratio 0.25)
      (net 1 "GND") (pintype "passive"))
  )
	(footprint "kria-k26-devboard-footprints:C_0402_1005Metric" (layer "F.Cu")
    (at 130 90.7 180)
    (descr "Capacitor SMD 0402")
    (tags "capacitor SMD 0402")
    (property "Author" "Antmicro")
    (property "Dielectric" "")
    (property "License" "Apache-2.0")
    (property "MPN" "GRM155R61A475MEAAD")
    (property "Manufacturer" "Murata")
    (property "Sheetfile" "usb.kicad_sch")
    (property "Sheetname" "USB")
    (property "Val" "4u7")
    (property "Voltage" "")
    (property "ki_description" " ")
    (attr smd)
    (fp_text reference "C40" (at -0.72 -0.4 180) (layer "F.SilkS")
        (effects (font (size 0.7 0.7) (thickness 0.15)) (justify left bottom))
    )
    (fp_text value "C_4u7_0402" (at 0 1.4 180) (layer "F.Fab") hide
        (effects (font (size 0.7 0.7) (thickness 0.15)) (justify left bottom))
    )
    (fp_text user "Author: Antmicro" (at -0.932 4.17 180) (layer "F.Fab") hide
        (effects (font (size 0.7 0.7) (thickness 0.15)) (justify left bottom))
    )
    (fp_text user "License: Apache-2.0" (at -0.932 5.17 180) (layer "F.Fab") hide
        (effects (font (size 0.7 0.7) (thickness 0.15)) (justify left bottom))
    )
    (fp_text user "${REFERENCE}" (at -0.932 3.168 180) (layer "F.Fab") hide
        (effects (font (size 0.7 0.7) (thickness 0.15)) (justify left bottom))
    )
    (fp_rect (start -0.94 -0.47) (end 0.94 0.47)
      (stroke (width 0.05) (type solid)) (fill none) (layer "F.CrtYd"))
    (fp_rect (start -0.499 -0.249) (end 0.499 0.249)
      (stroke (width 0.15) (type solid)) (fill none) (layer "F.Fab"))
    (pad "1" smd roundrect (at -0.484 0 180) (size 0.59 0.64) (layers "F.Cu" "F.Paste" "F.Mask") (roundrect_rratio 0.25)
      (net 18 "PS_1V2") (pintype "passive"))
    (pad "2" smd roundrect (at 0.484 0 180) (size 0.59 0.64) (layers "F.Cu" "F.Paste" "F.Mask") (roundrect_rratio 0.25)
      (net 1 "GND") (pintype "passive"))
  )
	(footprint "kria-k26-devboard-footprints:D_SOD-323F" (layer "F.Cu")
    (at 94.89 141.6 -90)
    (property "Author" "Antmicro")
    (property "License" "Apache-2.0")
    (property "MPN" "1N4148WS")
    (property "Manufacturer" "ON Semiconductor")
    (property "Sheetfile" "reset.kicad_sch")
    (property "Sheetname" "Reset logic")
    (property "ki_description" "Small Signal Fast Switching Diode")
    (attr smd)
    (fp_text reference "D4" (at 2.25 0.91 -90) (layer "F.SilkS")
        (effects (font (size 0.7 0.7) (thickness 0.15)) (justify left bottom))
    )
    (fp_text value "1N4148WS" (at -1.7 1.9 -90) (layer "F.Fab") hide
        (effects (font (size 0.7 0.7) (thickness 0.15)) (justify left bottom))
    )
    (fp_text user "License: Apache-2.0" (at -1.8 5.8 -90) (layer "F.Fab") hide
        (effects (font (size 0.7 0.7) (thickness 0.15)) (justify left bottom))
    )
    (fp_text user "${REFERENCE}" (at -1.8 3.2 -90) (layer "F.Fab") hide
        (effects (font (size 0.7 0.7) (thickness 0.15)) (justify left bottom))
    )
    (fp_text user "Author: Antmicro" (at -1.8 4.46 -90) (layer "F.Fab") hide
        (effects (font (size 0.7 0.7) (thickness 0.15)) (justify left bottom))
    )
    (fp_line (start -0.975 -0.75) (end -0.975 -0.45)
      (stroke (width 0.15) (type solid)) (layer "F.SilkS"))
    (fp_line (start -0.975 0.748) (end -0.975 0.45)
      (stroke (width 0.15) (type solid)) (layer "F.SilkS"))
    (fp_line (start -0.625 -0.75) (end -0.975 -0.75)
      (stroke (width 0.15) (type solid)) (layer "F.SilkS"))
    (fp_line (start -0.625 0.748) (end -0.975 0.748)
      (stroke (width 0.15) (type solid)) (layer "F.SilkS"))
    (fp_line (start -0.5 -0.426) (end -0.5 0.424)
      (stroke (width 0.15) (type solid)) (layer "F.SilkS"))
    (fp_line (start 0.623 -0.75) (end 0.973 -0.75)
      (stroke (width 0.15) (type solid)) (layer "F.SilkS"))
    (fp_line (start 0.973 -0.75) (end 0.973 -0.45)
      (stroke (width 0.15) (type solid)) (layer "F.SilkS"))
    (fp_line (start 0.973 0.45) (end 0.973 0.748)
      (stroke (width 0.15) (type solid)) (layer "F.SilkS"))
    (fp_line (start 0.973 0.748) (end 0.623 0.748)
      (stroke (width 0.15) (type solid)) (layer "F.SilkS"))
    (fp_rect (start -1.6 -0.827) (end 1.599 0.825)
      (stroke (width 0.05) (type solid)) (fill none) (layer "F.CrtYd"))
    (fp_line (start -0.85 -0.625) (end 0.848 -0.625)
      (stroke (width 0.15) (type solid)) (layer "F.Fab"))
    (fp_line (start -0.85 0.623) (end -0.85 -0.625)
      (stroke (width 0.15) (type solid)) (layer "F.Fab"))
    (fp_line (start -0.85 0.623) (end 0.848 0.623)
      (stroke (width 0.15) (type solid)) (layer "F.Fab"))
    (fp_line (start 0.848 -0.625) (end 0.848 0.623)
      (stroke (width 0.15) (type solid)) (layer "F.Fab"))
    (pad "A" smd roundrect (at 1.05 0 270) (size 0.8 0.6) (layers "F.Cu" "F.Paste" "F.Mask") (roundrect_rratio 0.15)
      (net 335 "Net-(U32-MR_N)") (pinfunction "A") (pintype "passive"))
    (pad "K" smd roundrect (at -1.051 0 270) (size 0.8 0.6) (layers "F.Cu" "F.Paste" "F.Mask") (roundrect_rratio 0.15)
      (net 327 "Net-(D4-PadK)") (pinfunction "K") (pintype "passive"))
  )
	(footprint "kria-k26-devboard-footprints:C_0402_1005Metric" (layer "F.Cu")
    (at 98.315 144.3)
    (descr "Capacitor SMD 0402")
    (tags "capacitor SMD 0402")
    (property "Author" "Antmicro")
    (property "Dielectric" "X5R")
    (property "License" "Apache-2.0")
    (property "MPN" "GRM155R61H104KE14D")
    (property "Manufacturer" "Murata")
    (property "Sheetfile" "reset.kicad_sch")
    (property "Sheetname" "Reset logic")
    (property "Val" "100n")
    (property "Voltage" "50V")
    (property "ki_description" " ")
    (attr smd)
    (fp_text reference "C133" (at -1.165 1.3) (layer "F.SilkS")
        (effects (font (size 0.7 0.7) (thickness 0.15)) (justify left bottom))
    )
    (fp_text value "C_100n_0402" (at 0 1.4) (layer "F.Fab") hide
        (effects (font (size 0.7 0.7) (thickness 0.15)) (justify left bottom))
    )
    (fp_text user "Author: Antmicro" (at -0.932 4.17) (layer "F.Fab") hide
        (effects (font (size 0.7 0.7) (thickness 0.15)) (justify left bottom))
    )
    (fp_text user "${REFERENCE}" (at -0.932 3.168) (layer "F.Fab") hide
        (effects (font (size 0.7 0.7) (thickness 0.15)) (justify left bottom))
    )
    (fp_text user "License: Apache-2.0" (at -0.932 5.17) (layer "F.Fab") hide
        (effects (font (size 0.7 0.7) (thickness 0.15)) (justify left bottom))
    )
    (fp_rect (start -0.94 -0.47) (end 0.94 0.47)
      (stroke (width 0.05) (type solid)) (fill none) (layer "F.CrtYd"))
    (fp_rect (start -0.499 -0.249) (end 0.499 0.249)
      (stroke (width 0.15) (type solid)) (fill none) (layer "F.Fab"))
    (pad "1" smd roundrect (at -0.484 0) (size 0.59 0.64) (layers "F.Cu" "F.Paste" "F.Mask") (roundrect_rratio 0.25)
      (net 20 "PL_3V3") (pintype "passive"))
    (pad "2" smd roundrect (at 0.484 0) (size 0.59 0.64) (layers "F.Cu" "F.Paste" "F.Mask") (roundrect_rratio 0.25)
      (net 1 "GND") (pintype "passive"))
  )
	(footprint "kria-k26-devboard-footprints:SOT-753" (layer "F.Cu")
    (at 95.514999 145.875 180)
    (property "Author" "Antmicro")
    (property "License" "Apache-2.0")
    (property "MPN" "SN74LVC1G125DBVR")
    (property "Manufacturer" "Texas Instruments")
    (property "Sheetfile" "reset.kicad_sch")
    (property "Sheetname" "Reset logic")
    (property "ki_description" "Buffer, 74LVC1G125, 1.65 V to 5.5 V, SOT-23-5")
    (property "ki_keywords" "SMT, LOGIC, IC, BUFFER, TRANSCEIVER, DRIVER")
    (attr smd)
    (fp_text reference "U35" (at 1.864999 -1.175 270) (layer "F.SilkS")
        (effects (font (size 0.7 0.7) (thickness 0.15)) (justify left bottom))
    )
    (fp_text value "SN74LVC1G125_SOT" (at 0 2.9 180) (layer "F.Fab") hide
        (effects (font (size 0.7 0.7) (thickness 0.15)) (justify left bottom))
    )
    (fp_text user "License: Apache-2.0" (at -1.651 8.425 180) (layer "F.Fab") hide
        (effects (font (size 0.7 0.7) (thickness 0.15)) (justify left bottom))
    )
    (fp_text user "${REFERENCE}" (at -1.651 6.025 180) (layer "F.Fab") hide
        (effects (font (size 0.7 0.7) (thickness 0.15)) (justify left bottom))
    )
    (fp_text user "Author: Antmicro" (at -1.651 7.225 180) (layer "F.Fab") hide
        (effects (font (size 0.7 0.7) (thickness 0.15)) (justify left bottom))
    )
    (fp_line (start -1.651 -1) (end -1.651 -0.701)
      (stroke (width 0.15) (type solid)) (layer "F.SilkS"))
    (fp_line (start -1.648 1) (end -1.648 0.677)
      (stroke (width 0.15) (type solid)) (layer "F.SilkS"))
    (fp_line (start -1.5 -1) (end -1.651 -1)
      (stroke (width 0.15) (type solid)) (layer "F.SilkS"))
    (fp_line (start -1.5 1) (end -1.648 1)
      (stroke (width 0.15) (type solid)) (layer "F.SilkS"))
    (fp_line (start 1.5 -1) (end 1.648 -1)
      (stroke (width 0.15) (type solid)) (layer "F.SilkS"))
    (fp_line (start 1.5 0.998) (end 1.648 0.998)
      (stroke (width 0.15) (type solid)) (layer "F.SilkS"))
    (fp_line (start 1.648 -1) (end 1.648 -0.677)
      (stroke (width 0.15) (type solid)) (layer "F.SilkS"))
    (fp_line (start 1.648 0.998) (end 1.648 0.699)
      (stroke (width 0.15) (type solid)) (layer "F.SilkS"))
    (fp_circle (center -1.5 1.35) (end -1.46 1.4)
      (stroke (width 0.15) (type solid)) (fill solid) (layer "F.SilkS"))
    (fp_rect (start -1.7 -1.901) (end 1.699 1.898)
      (stroke (width 0.05) (type solid)) (fill none) (layer "F.CrtYd"))
    (fp_line (start -1.526 -0.875) (end 1.523 -0.875)
      (stroke (width 0.15) (type solid)) (layer "F.Fab"))
    (fp_line (start -1.526 0.623) (end -1.526 -0.875)
      (stroke (width 0.15) (type solid)) (layer "F.Fab"))
    (fp_line (start -1.526 0.623) (end -1.351 0.873)
      (stroke (width 0.15) (type solid)) (layer "F.Fab"))
    (fp_line (start -1.351 0.873) (end 1.523 0.873)
      (stroke (width 0.15) (type solid)) (layer "F.Fab"))
    (fp_line (start 1.523 -0.875) (end 1.523 0.873)
      (stroke (width 0.15) (type solid)) (layer "F.Fab"))
    (pad "1" smd roundrect (at -0.951 1.35 180) (size 0.6 1.05) (layers "F.Cu" "F.Paste" "F.Mask") (roundrect_rratio 0.25)
      (net 174 "/Reset logic/PL_RST") (pinfunction "~{OE}") (pintype "input"))
    (pad "2" smd roundrect (at 0 1.35 180) (size 0.6 1.05) (layers "F.Cu" "F.Paste" "F.Mask") (roundrect_rratio 0.25)
      (net 129 "/Reset logic/HDA02") (pinfunction "A") (pintype "input"))
    (pad "3" smd roundrect (at 0.949 1.35 180) (size 0.6 1.05) (layers "F.Cu" "F.Paste" "F.Mask") (roundrect_rratio 0.25)
      (net 1 "GND") (pinfunction "GND") (pintype "power_in"))
    (pad "4" smd roundrect (at 0.949 -1.351 180) (size 0.6 1.05) (layers "F.Cu" "F.Paste" "F.Mask") (roundrect_rratio 0.25)
      (net 198 "/Camera interface/CAM0_RST") (pinfunction "Y") (pintype "output"))
    (pad "5" smd roundrect (at -0.951 -1.351 180) (size 0.6 1.05) (layers "F.Cu" "F.Paste" "F.Mask") (roundrect_rratio 0.25)
      (net 20 "PL_3V3") (pinfunction "V_{CC}") (pintype "power_in"))
  )
)
